# T6G (Grand Teton) — schematic netlist excerpt (pin names and nets, part order shuffled) for the footprints in the layout excerpt that follows; sources: Cadence DE-HDL packaged netlist, KiCad conversion of 04192023_DAF0TMB3IC0_F0TG_MB_C_brd_V02_OCP.brd

R200  Q_RES  4.7K 5% EMPTY  pkg 0402LF  page 160 : A = P3V3_AUX ; B = PU_U96_EN
C588  Q_CAP  100UF 4V 20% X6S  pkg C0805  page 290 : A = P1V8_CPU0_RT1_1A ; B = GND
PR885  Q_RES  5.36K 1% EMPTY  pkg 0402LF  page 364 : A = P5V_AUX ; B = P0V9_RETIMER_CPU1_VMON

(kicad_pcb
	(version 20260206)
	(generator "pcbnew")
	(generator_version "10.0")
	(general
		(thickness 1.6)
		(legacy_teardrops no)
	)
	(paper "A4")
	(title_block
		(title "04192023_DAF0TMB3IC0_F0TG_MB_C_brd_V02_OCP.brd")
		(comment 1 "Grand Teton / footprints 6320-6322 of 8354")
	)
	(layers
		(0 "F.Cu" signal "TOP")
		(4 "In1.Cu" signal "GND")
		(6 "In2.Cu" signal "IN1")
		(8 "In3.Cu" signal "GND1")
		(10 "In4.Cu" signal "IN2")
		(12 "In5.Cu" signal "GND2")
		(14 "In6.Cu" signal "IN3")
		(16 "In7.Cu" signal "GND3")
		(18 "In8.Cu" signal "VCC")
		(20 "In9.Cu" signal "VCC1")
		(22 "In10.Cu" signal "GND4")
		(24 "In11.Cu" signal "IN4")
		(26 "In12.Cu" signal "GND5")
		(28 "In13.Cu" signal "IN5")
		(30 "In14.Cu" signal "GND6")
		(32 "In15.Cu" signal "IN6")
		(34 "In16.Cu" signal "GND7")
		(2 "B.Cu" signal "BOTTOM")
		(9 "F.Adhes" user "F.Adhesive")
		(11 "B.Adhes" user "B.Adhesive")
		(13 "F.Paste" user "Package Geometry/Pastemask Top")
		(15 "B.Paste" user "Package Geometry/Pastemask Bottom")
		(5 "F.SilkS" user "Ref Des/Silkscreen Top")
		(7 "B.SilkS" user "Ref Des/Silkscreen Bottom")
		(1 "F.Mask" user "Board Geometry/Soldermask Top")
		(3 "B.Mask" user "Board Geometry/Soldermask Bottom")
		(17 "Dwgs.User" user "User.Drawings")
		(19 "Cmts.User" user "User.Comments")
		(21 "Eco1.User" user "User.Eco1")
		(23 "Eco2.User" user "User.Eco2")
		(25 "Edge.Cuts" user "Board Geometry/Outline")
		(27 "Margin" user)
		(31 "F.CrtYd" user "Package Geometry/Place Bound Top")
		(29 "B.CrtYd" user "Package Geometry/Place Bound Bottom")
		(35 "F.Fab" user "Ref Des/Assembly Top")
		(33 "B.Fab" user "Ref Des/Assembly Bottom")
	)
	(footprint ""
		(layer "B.Cu")
		(at 244.729 -218.186 -90)
		(property "Reference" "R200"
			(at 0 0 90)
			(layer "B.SilkS")
			(hide yes)
			(effects
				(font
					(size 1.27 1.27)
				)
				(justify mirror)
			)
		)
		(property "Value" ""
			(at 0 0 90)
			(layer "B.Fab")
			(effects
				(font
					(size 1.27 1.27)
				)
				(justify mirror)
			)
		)
		(duplicate_pad_numbers_are_jumpers no)
		(fp_line
			(start -0.7874 0.4064)
			(end 0.7874 0.4064)
			(stroke
				(width 0.1524)
				(type default)
			)
			(layer "B.SilkS")
		)
		(fp_line
			(start 0.7874 0.4064)
			(end 0.7874 -0.4064)
			(stroke
				(width 0.1524)
				(type default)
			)
			(layer "B.SilkS")
		)
		(fp_line
			(start -0.7874 -0.4064)
			(end -0.7874 0.4064)
			(stroke
				(width 0.1524)
				(type default)
			)
			(layer "B.SilkS")
		)
		(fp_line
			(start 0.7874 -0.4064)
			(end -0.7874 -0.4064)
			(stroke
				(width 0.1524)
				(type default)
			)
			(layer "B.SilkS")
		)
		(fp_line
			(start -0.67945 0.3048)
			(end -0.120396 0.3048)
			(stroke
				(width 0.1)
				(type default)
			)
			(layer "B.Fab")
		)
		(fp_line
			(start -0.120396 0.3048)
			(end -0.120396 0.2794)
			(stroke
				(width 0.1)
				(type default)
			)
			(layer "B.Fab")
		)
		(fp_line
			(start 0.12065 0.3048)
			(end 0.67945 0.3048)
			(stroke
				(width 0.1)
				(type default)
			)
			(layer "B.Fab")
		)
		(fp_line
			(start 0.67945 0.3048)
			(end 0.67945 -0.305054)
			(stroke
				(width 0.1)
				(type default)
			)
			(layer "B.Fab")
		)
		(fp_line
			(start -0.120396 0.2794)
			(end 0.12065 0.2794)
			(stroke
				(width 0.1)
				(type default)
			)
			(layer "B.Fab")
		)
		(fp_line
			(start 0.12065 0.2794)
			(end 0.12065 0.3048)
			(stroke
				(width 0.1)
				(type default)
			)
			(layer "B.Fab")
		)
		(fp_line
			(start -0.12065 -0.2794)
			(end -0.12065 -0.3048)
			(stroke
				(width 0.1)
				(type default)
			)
			(layer "B.Fab")
		)
		(fp_line
			(start 0.12065 -0.2794)
			(end -0.12065 -0.2794)
			(stroke
				(width 0.1)
				(type default)
			)
			(layer "B.Fab")
		)
		(fp_line
			(start -0.67945 -0.3048)
			(end -0.67945 0.3048)
			(stroke
				(width 0.1)
				(type default)
			)
			(layer "B.Fab")
		)
		(fp_line
			(start -0.12065 -0.3048)
			(end -0.67945 -0.3048)
			(stroke
				(width 0.1)
				(type default)
			)
			(layer "B.Fab")
		)
		(fp_line
			(start 0.12065 -0.305054)
			(end 0.12065 -0.2794)
			(stroke
				(width 0.1)
				(type default)
			)
			(layer "B.Fab")
		)
		(fp_line
			(start 0.67945 -0.305054)
			(end 0.12065 -0.305054)
			(stroke
				(width 0.1)
				(type default)
			)
			(layer "B.Fab")
		)
		(pad "1" smd circle
			(at 0.40005 0 90)
			(size 0 0)
			(layers "B.Cu" "B.Mask" "B.Paste")
			(net "P3V3_AUX")
		)
		(pad "2" smd circle
			(at -0.40005 0 90)
			(size 0 0)
			(layers "B.Cu" "B.Mask" "B.Paste")
			(net "PU_U96_EN")
		)
	)
	(footprint ""
		(layer "B.Cu")
		(at 357.443786 -395.466062 -90)
		(property "Reference" "C588"
			(at 0 0 90)
			(layer "B.SilkS")
			(hide yes)
			(effects
				(font
					(size 1.27 1.27)
				)
				(justify mirror)
			)
		)
		(property "Value" ""
			(at 0 0 90)
			(layer "B.Fab")
			(effects
				(font
					(size 1.27 1.27)
				)
				(justify mirror)
			)
		)
		(duplicate_pad_numbers_are_jumpers no)
		(fp_line
			(start -1.524 0.762)
			(end 1.524 0.762)
			(stroke
				(width 0.1524)
				(type default)
			)
			(layer "B.SilkS")
		)
		(fp_line
			(start 1.524 0.762)
			(end 1.524 -0.762)
			(stroke
				(width 0.1524)
				(type default)
			)
			(layer "B.SilkS")
		)
		(fp_line
			(start -1.524 -0.762)
			(end -1.524 0.762)
			(stroke
				(width 0.1524)
				(type default)
			)
			(layer "B.SilkS")
		)
		(fp_line
			(start 1.524 -0.762)
			(end -1.524 -0.762)
			(stroke
				(width 0.1524)
				(type default)
			)
			(layer "B.SilkS")
		)
		(fp_line
			(start -1.1049 0.724916)
			(end -1.1049 -0.724916)
			(stroke
				(width 0.1)
				(type default)
			)
			(layer "B.Fab")
		)
		(fp_line
			(start 1.1049 0.724916)
			(end -1.1049 0.724916)
			(stroke
				(width 0.1)
				(type default)
			)
			(layer "B.Fab")
		)
		(fp_line
			(start -1.1049 -0.724916)
			(end 1.1049 -0.724916)
			(stroke
				(width 0.1)
				(type default)
			)
			(layer "B.Fab")
		)
		(fp_line
			(start 1.1049 -0.724916)
			(end 1.1049 0.724916)
			(stroke
				(width 0.1)
				(type default)
			)
			(layer "B.Fab")
		)
		(pad "1" smd rect
			(at 0.889 0 270)
			(size 1.016 1.27)
			(layers "B.Cu" "B.Mask" "B.Paste")
			(net "P1V8_CPU0_RT1_1A")
		)
		(pad "2" smd rect
			(at -0.889 0 270)
			(size 1.016 1.27)
			(layers "B.Cu" "B.Mask" "B.Paste")
			(net "GND")
		)
	)
	(footprint ""
		(layer "B.Cu")
		(at 11.853418 -412.85287 180)
		(property "Reference" "PR885"
			(at 0 0 0)
			(layer "B.SilkS")
			(hide yes)
			(effects
				(font
					(size 1.27 1.27)
				)
				(justify mirror)
			)
		)
		(property "Value" ""
			(at 0 0 0)
			(layer "B.Fab")
			(effects
				(font
					(size 1.27 1.27)
				)
				(justify mirror)
			)
		)
		(duplicate_pad_numbers_are_jumpers no)
		(fp_line
			(start 0.7874 0.4064)
			(end 0.7874 -0.4064)
			(stroke
				(width 0.1524)
				(type default)
			)
			(layer "B.SilkS")
		)
		(fp_line
			(start 0.7874 -0.4064)
			(end -0.7874 -0.4064)
			(stroke
				(width 0.1524)
				(type default)
			)
			(layer "B.SilkS")
		)
		(fp_line
			(start -0.7874 0.4064)
			(end 0.7874 0.4064)
			(stroke
				(width 0.1524)
				(type default)
			)
			(layer "B.SilkS")
		)
		(fp_line
			(start -0.7874 -0.4064)
			(end -0.7874 0.4064)
			(stroke
				(width 0.1524)
				(type default)
			)
			(layer "B.SilkS")
		)
		(fp_line
			(start 0.67945 0.3048)
			(end 0.67945 -0.305054)
			(stroke
				(width 0.1)
				(type default)
			)
			(layer "B.Fab")
		)
		(fp_line
			(start 0.67945 -0.305054)
			(end 0.12065 -0.305054)
			(stroke
				(width 0.1)
				(type default)
			)
			(layer "B.Fab")
		)
		(fp_line
			(start 0.12065 0.3048)
			(end 0.67945 0.3048)
			(stroke
				(width 0.1)
				(type default)
			)
			(layer "B.Fab")
		)
		(fp_line
			(start 0.12065 0.2794)
			(end 0.12065 0.3048)
			(stroke
				(width 0.1)
				(type default)
			)
			(layer "B.Fab")
		)
		(fp_line
			(start 0.12065 -0.2794)
			(end -0.12065 -0.2794)
			(stroke
				(width 0.1)
				(type default)
			)
			(layer "B.Fab")
		)
		(fp_line
			(start 0.12065 -0.305054)
			(end 0.12065 -0.2794)
			(stroke
				(width 0.1)
				(type default)
			)
			(layer "B.Fab")
		)
		(fp_line
			(start -0.120396 0.3048)
			(end -0.120396 0.2794)
			(stroke
				(width 0.1)
				(type default)
			)
			(layer "B.Fab")
		)
		(fp_line
			(start -0.120396 0.2794)
			(end 0.12065 0.2794)
			(stroke
				(width 0.1)
				(type default)
			)
			(layer "B.Fab")
		)
		(fp_line
			(start -0.12065 -0.2794)
			(end -0.12065 -0.3048)
			(stroke
				(width 0.1)
				(type default)
			)
			(layer "B.Fab")
		)
		(fp_line
			(start -0.12065 -0.3048)
			(end -0.67945 -0.3048)
			(stroke
				(width 0.1)
				(type default)
			)
			(layer "B.Fab")
		)
		(fp_line
			(start -0.67945 0.3048)
			(end -0.120396 0.3048)
			(stroke
				(width 0.1)
				(type default)
			)
			(layer "B.Fab")
		)
		(fp_line
			(start -0.67945 -0.3048)
			(end -0.67945 0.3048)
			(stroke
				(width 0.1)
				(type default)
			)
			(layer "B.Fab")
		)
		(pad "1" smd circle
			(at 0.40005 0)
			(size 0 0)
			(layers "B.Cu" "B.Mask" "B.Paste")
			(net "P5V_AUX")
		)
		(pad "2" smd circle
			(at -0.40005 0)
			(size 0 0)
			(layers "B.Cu" "B.Mask" "B.Paste")
			(net "P0V9_RETIMER_CPU1_VMON")
		)
	)
)
